(kicad_pcb
	(version 20260206)
	(generator "pcbnew")
	(generator_version "10.0")
	(general
		(thickness 1.6)
		(legacy_teardrops no)
	)
	(paper "A4")
	(title_block
		(title "Wiwynn_Tioga_Pass_MB.brd")
		(comment 1 "Tioga Pass / footprints 3938-3944 of 4770")
	)
	(layers
		(0 "F.Cu" signal "TOP")
		(4 "In1.Cu" signal "L2GND")
		(6 "In2.Cu" signal "L3")
		(8 "In3.Cu" signal "L4GND")
		(10 "In4.Cu" signal "L5")
		(12 "In5.Cu" signal "L6GND")
		(14 "In6.Cu" signal "L7VCC")
		(16 "In7.Cu" signal "L8VCC")
		(18 "In8.Cu" signal "L9GND")
		(20 "In9.Cu" signal "L10")
		(22 "In10.Cu" signal "L11GND")
		(24 "In11.Cu" signal "L12")
		(26 "In12.Cu" signal "L13GND")
		(2 "B.Cu" signal "BOTTOM")
		(9 "F.Adhes" user "F.Adhesive")
		(11 "B.Adhes" user "B.Adhesive")
		(13 "F.Paste" user "Package Geometry/Pastemask Top")
		(15 "B.Paste" user "Package Geometry/Pastemask Bottom")
		(5 "F.SilkS" user "Ref Des/Silkscreen Top")
		(7 "B.SilkS" user "Ref Des/Silkscreen Bottom")
		(1 "F.Mask" user "Board Geometry/Soldermask Top")
		(3 "B.Mask" user "Board Geometry/Soldermask Bottom")
		(17 "Dwgs.User" user "User.Drawings")
		(19 "Cmts.User" user "User.Comments")
		(21 "Eco1.User" user "User.Eco1")
		(23 "Eco2.User" user "User.Eco2")
		(25 "Edge.Cuts" user "Board Geometry/Outline")
		(27 "Margin" user)
		(31 "F.CrtYd" user "Package Geometry/Place Bound Top")
		(29 "B.CrtYd" user "Package Geometry/Place Bound Bottom")
		(35 "F.Fab" user "Ref Des/Assembly Top")
		(33 "B.Fab" user "Ref Des/Assembly Bottom")
	)
	(footprint ""
		(layer "B.Cu")
		(at 411.505146 -34.934652 -90)
		(property "Reference" "C25W49"
			(at 0.8382 -0.67818 270)
			(unlocked yes)
			(layer "B.SilkS")
			(effects
				(font
					(size 0.4064 0.254)
					(thickness 0.1524)
				)
				(justify left mirror)
			)
		)
		(property "Value" ""
			(at 0 0 90)
			(layer "B.Fab")
			(effects
				(font
					(size 1.27 1.27)
				)
				(justify mirror)
			)
		)
		(duplicate_pad_numbers_are_jumpers no)
		(fp_poly
			(pts
				(xy -0.3048 -0.1016) (xy -0.3048 0.9906) (xy 0.3048 0.9906) (xy 0.3048 -0.1016)
			)
			(stroke
				(width 0)
				(type default)
			)
			(fill no)
			(layer "B.CrtYd")
		)
		(fp_line
			(start -0.3048 0.9906)
			(end -0.3048 -0.1016)
			(stroke
				(width 0.1)
				(type default)
			)
			(layer "B.Fab")
		)
		(fp_line
			(start 0.3048 0.9906)
			(end -0.3048 0.9906)
			(stroke
				(width 0.1)
				(type default)
			)
			(layer "B.Fab")
		)
		(fp_line
			(start -0.3048 -0.1016)
			(end 0.3048 -0.1016)
			(stroke
				(width 0.1)
				(type default)
			)
			(layer "B.Fab")
		)
		(fp_line
			(start 0.3048 -0.1016)
			(end 0.3048 0.9906)
			(stroke
				(width 0.1)
				(type default)
			)
			(layer "B.Fab")
		)
		(pad "1" smd rect
			(at 0 0 90)
			(size 0.508 0.508)
			(layers "B.Cu" "B.Mask" "B.Paste")
			(net "P3V3_STBY")
		)
		(pad "2" smd rect
			(at 0 0.889 90)
			(size 0.508 0.508)
			(layers "B.Cu" "B.Mask" "B.Paste")
			(net "GND")
		)
		(zone
			(layer "B.Cu")
			(hatch none 0.5)
			(connect_pads
				(clearance 0)
			)
			(min_thickness 0.25)
			(keepout
				(tracks not_allowed)
				(vias allowed)
				(pads allowed)
				(copperpour not_allowed)
				(footprints allowed)
			)
			(placement
				(enabled no)
				(sheetname "")
			)
			(fill
				(thermal_gap 0.5)
				(thermal_bridge_width 0.5)
				(island_removal_mode 0)
			)
			(polygon
				(pts
					(xy 410.870146 -34.680652) (xy 410.870146 -35.188652) (xy 411.251146 -35.188652) (xy 411.251146 -34.680652)
				)
			)
		)
		(zone
			(layer "B.Cu")
			(hatch none 0.5)
			(connect_pads
				(clearance 0)
			)
			(min_thickness 0.25)
			(keepout
				(tracks allowed)
				(vias not_allowed)
				(pads allowed)
				(copperpour not_allowed)
				(footprints allowed)
			)
			(placement
				(enabled no)
				(sheetname "")
			)
			(fill
				(thermal_gap 0.5)
				(thermal_bridge_width 0.5)
				(island_removal_mode 0)
			)
			(polygon
				(pts
					(xy 411.251146 -34.680652) (xy 411.251146 -35.188652) (xy 410.870146 -35.188652) (xy 410.870146 -34.680652)
				)
			)
		)
	)
	(footprint ""
		(layer "B.Cu")
		(at 482.592888 -154.917902 -90)
		(property "Reference" "F1L1"
			(at 0 0 90)
			(layer "B.SilkS")
			(hide yes)
			(effects
				(font
					(size 1.27 1.27)
				)
				(justify mirror)
			)
		)
		(property "Value" ""
			(at 0 0 90)
			(layer "B.Fab")
			(effects
				(font
					(size 1.27 1.27)
				)
				(justify mirror)
			)
		)
		(duplicate_pad_numbers_are_jumpers no)
		(fp_poly
			(pts
				(xy 0.2032 -0.4953) (xy 0.2032 0.4953) (xy -1.6002 0.4953) (xy -1.6002 -0.4953)
			)
			(stroke
				(width 0)
				(type default)
			)
			(fill no)
			(layer "B.CrtYd")
		)
		(fp_line
			(start -1.6002 0.4953)
			(end 0.2032 0.4953)
			(stroke
				(width 0.1)
				(type default)
			)
			(layer "B.Fab")
		)
		(fp_line
			(start 0.2032 0.4953)
			(end 0.2032 -0.4953)
			(stroke
				(width 0.1)
				(type default)
			)
			(layer "B.Fab")
		)
		(fp_line
			(start -1.6002 -0.4953)
			(end -1.6002 0.4953)
			(stroke
				(width 0.1)
				(type default)
			)
			(layer "B.Fab")
		)
		(fp_line
			(start 0.2032 -0.4953)
			(end -1.6002 -0.4953)
			(stroke
				(width 0.1)
				(type default)
			)
			(layer "B.Fab")
		)
		(pad "1" smd rect
			(at 0 0 90)
			(size 0.889 0.9906)
			(layers "B.Cu" "B.Mask" "B.Paste")
			(net "P5V_STBY_DBG")
		)
		(pad "2" smd rect
			(at -1.397 0 90)
			(size 0.889 0.9906)
			(layers "B.Cu" "B.Mask" "B.Paste")
			(net "P5V_STBY_DGB_FS")
		)
		(zone
			(layer "B.Cu")
			(hatch none 0.5)
			(connect_pads
				(clearance 0)
			)
			(min_thickness 0.25)
			(keepout
				(tracks not_allowed)
				(vias allowed)
				(pads allowed)
				(copperpour not_allowed)
				(footprints allowed)
			)
			(placement
				(enabled no)
				(sheetname "")
			)
			(fill
				(thermal_gap 0.5)
				(thermal_bridge_width 0.5)
				(island_removal_mode 0)
			)
			(polygon
				(pts
					(xy 483.088188 -155.362402) (xy 482.097588 -155.362402) (xy 482.097588 -155.870402) (xy 483.088188 -155.870402)
				)
			)
		)
	)
	(footprint ""
		(layer "B.Cu")
		(at 451.030594 -17.1831 -90)
		(property "Reference" "R3W1"
			(at 0.8382 -0.67818 270)
			(unlocked yes)
			(layer "B.SilkS")
			(effects
				(font
					(size 0.4064 0.254)
					(thickness 0.1524)
				)
				(justify left mirror)
			)
		)
		(property "Value" ""
			(at 0 0 90)
			(layer "B.Fab")
			(effects
				(font
					(size 1.27 1.27)
				)
				(justify mirror)
			)
		)
		(duplicate_pad_numbers_are_jumpers no)
		(fp_poly
			(pts
				(xy 0.2794 -0.1016) (xy -0.2794 -0.1016) (xy -0.2794 0.9906) (xy 0.2794 0.9906)
			)
			(stroke
				(width 0)
				(type default)
			)
			(fill no)
			(layer "B.CrtYd")
		)
		(fp_line
			(start -0.2794 0.9906)
			(end -0.2794 -0.1016)
			(stroke
				(width 0.1)
				(type default)
			)
			(layer "B.Fab")
		)
		(fp_line
			(start 0.2794 0.9906)
			(end -0.2794 0.9906)
			(stroke
				(width 0.1)
				(type default)
			)
			(layer "B.Fab")
		)
		(fp_line
			(start -0.2794 -0.1016)
			(end 0.2794 -0.1016)
			(stroke
				(width 0.1)
				(type default)
			)
			(layer "B.Fab")
		)
		(fp_line
			(start 0.2794 -0.1016)
			(end 0.2794 0.9906)
			(stroke
				(width 0.1)
				(type default)
			)
			(layer "B.Fab")
		)
		(pad "1" smd rect
			(at 0 0 90)
			(size 0.508 0.508)
			(layers "B.Cu" "B.Mask" "B.Paste")
			(net "BMC_SELF_HW_D_RST")
		)
		(pad "2" smd rect
			(at 0 0.889 90)
			(size 0.508 0.508)
			(layers "B.Cu" "B.Mask" "B.Paste")
			(net "GND")
		)
		(zone
			(layer "B.Cu")
			(hatch none 0.5)
			(connect_pads
				(clearance 0)
			)
			(min_thickness 0.25)
			(keepout
				(tracks not_allowed)
				(vias allowed)
				(pads allowed)
				(copperpour not_allowed)
				(footprints allowed)
			)
			(placement
				(enabled no)
				(sheetname "")
			)
			(fill
				(thermal_gap 0.5)
				(thermal_bridge_width 0.5)
				(island_removal_mode 0)
			)
			(polygon
				(pts
					(xy 450.395594 -16.9291) (xy 450.395594 -17.4371) (xy 450.776594 -17.4371) (xy 450.776594 -16.9291)
				)
			)
		)
		(zone
			(layer "B.Cu")
			(hatch none 0.5)
			(connect_pads
				(clearance 0)
			)
			(min_thickness 0.25)
			(keepout
				(tracks allowed)
				(vias not_allowed)
				(pads allowed)
				(copperpour not_allowed)
				(footprints allowed)
			)
			(placement
				(enabled no)
				(sheetname "")
			)
			(fill
				(thermal_gap 0.5)
				(thermal_bridge_width 0.5)
				(island_removal_mode 0)
			)
			(polygon
				(pts
					(xy 450.776594 -16.9291) (xy 450.776594 -17.4371) (xy 450.395594 -17.4371) (xy 450.395594 -16.9291)
				)
			)
		)
	)
	(footprint ""
		(layer "B.Cu")
		(at 454.5838 -146.7612 -90)
		(property "Reference" "C9A5"
			(at 0 0 90)
			(layer "B.SilkS")
			(hide yes)
			(effects
				(font
					(size 1.27 1.27)
				)
				(justify mirror)
			)
		)
		(property "Value" ""
			(at 0 0 90)
			(layer "B.Fab")
			(effects
				(font
					(size 1.27 1.27)
				)
				(justify mirror)
			)
		)
		(duplicate_pad_numbers_are_jumpers no)
		(fp_poly
			(pts
				(xy -0.3048 -0.1016) (xy -0.3048 0.9906) (xy 0.3048 0.9906) (xy 0.3048 -0.1016)
			)
			(stroke
				(width 0)
				(type default)
			)
			(fill no)
			(layer "B.CrtYd")
		)
		(fp_line
			(start -0.3048 0.9906)
			(end -0.3048 -0.1016)
			(stroke
				(width 0.1)
				(type default)
			)
			(layer "B.Fab")
		)
		(fp_line
			(start 0.3048 0.9906)
			(end -0.3048 0.9906)
			(stroke
				(width 0.1)
				(type default)
			)
			(layer "B.Fab")
		)
		(fp_line
			(start -0.3048 -0.1016)
			(end 0.3048 -0.1016)
			(stroke
				(width 0.1)
				(type default)
			)
			(layer "B.Fab")
		)
		(fp_line
			(start 0.3048 -0.1016)
			(end 0.3048 0.9906)
			(stroke
				(width 0.1)
				(type default)
			)
			(layer "B.Fab")
		)
		(pad "1" smd rect
			(at 0 0 90)
			(size 0.508 0.508)
			(layers "B.Cu" "B.Mask" "B.Paste")
			(net "XDP_RST_CO_N")
		)
		(pad "2" smd rect
			(at 0 0.889 90)
			(size 0.508 0.508)
			(layers "B.Cu" "B.Mask" "B.Paste")
			(net "GND")
		)
		(zone
			(layer "B.Cu")
			(hatch none 0.5)
			(connect_pads
				(clearance 0)
			)
			(min_thickness 0.25)
			(keepout
				(tracks not_allowed)
				(vias allowed)
				(pads allowed)
				(copperpour not_allowed)
				(footprints allowed)
			)
			(placement
				(enabled no)
				(sheetname "")
			)
			(fill
				(thermal_gap 0.5)
				(thermal_bridge_width 0.5)
				(island_removal_mode 0)
			)
			(polygon
				(pts
					(xy 453.9488 -146.5072) (xy 453.9488 -147.0152) (xy 454.3298 -147.0152) (xy 454.3298 -146.5072)
				)
			)
		)
		(zone
			(layer "B.Cu")
			(hatch none 0.5)
			(connect_pads
				(clearance 0)
			)
			(min_thickness 0.25)
			(keepout
				(tracks allowed)
				(vias not_allowed)
				(pads allowed)
				(copperpour not_allowed)
				(footprints allowed)
			)
			(placement
				(enabled no)
				(sheetname "")
			)
			(fill
				(thermal_gap 0.5)
				(thermal_bridge_width 0.5)
				(island_removal_mode 0)
			)
			(polygon
				(pts
					(xy 454.3298 -146.5072) (xy 454.3298 -147.0152) (xy 453.9488 -147.0152) (xy 453.9488 -146.5072)
				)
			)
		)
	)
	(footprint ""
		(layer "B.Cu")
		(at 427.4185 -20.32 90)
		(property "Reference" "R1U9"
			(at 0 0 90)
			(layer "B.SilkS")
			(hide yes)
			(effects
				(font
					(size 1.27 1.27)
				)
				(justify mirror)
			)
		)
		(property "Value" ""
			(at 0 0 90)
			(layer "B.Fab")
			(effects
				(font
					(size 1.27 1.27)
				)
				(justify mirror)
			)
		)
		(duplicate_pad_numbers_are_jumpers no)
		(fp_poly
			(pts
				(xy 0.2794 -0.1016) (xy -0.2794 -0.1016) (xy -0.2794 0.9906) (xy 0.2794 0.9906)
			)
			(stroke
				(width 0)
				(type default)
			)
			(fill no)
			(layer "B.CrtYd")
		)
		(fp_line
			(start 0.2794 -0.1016)
			(end 0.2794 0.9906)
			(stroke
				(width 0.1)
				(type default)
			)
			(layer "B.Fab")
		)
		(fp_line
			(start -0.2794 -0.1016)
			(end 0.2794 -0.1016)
			(stroke
				(width 0.1)
				(type default)
			)
			(layer "B.Fab")
		)
		(fp_line
			(start 0.2794 0.9906)
			(end -0.2794 0.9906)
			(stroke
				(width 0.1)
				(type default)
			)
			(layer "B.Fab")
		)
		(fp_line
			(start -0.2794 0.9906)
			(end -0.2794 -0.1016)
			(stroke
				(width 0.1)
				(type default)
			)
			(layer "B.Fab")
		)
		(pad "1" smd rect
			(at 0 0 270)
			(size 0.508 0.508)
			(layers "B.Cu" "B.Mask" "B.Paste")
			(net "SMB_SMLINK0_STBY_LVC3_SCL_R")
		)
		(pad "2" smd rect
			(at 0 0.889 270)
			(size 0.508 0.508)
			(layers "B.Cu" "B.Mask" "B.Paste")
			(net "SMB_SMLINK0_STBY_LVC3_SCL")
		)
		(zone
			(layer "B.Cu")
			(hatch none 0.5)
			(connect_pads
				(clearance 0)
			)
			(min_thickness 0.25)
			(keepout
				(tracks allowed)
				(vias not_allowed)
				(pads allowed)
				(copperpour not_allowed)
				(footprints allowed)
			)
			(placement
				(enabled no)
				(sheetname "")
			)
			(fill
				(thermal_gap 0.5)
				(thermal_bridge_width 0.5)
				(island_removal_mode 0)
			)
			(polygon
				(pts
					(xy 427.6725 -20.574) (xy 427.6725 -20.066) (xy 428.0535 -20.066) (xy 428.0535 -20.574)
				)
			)
		)
		(zone
			(layer "B.Cu")
			(hatch none 0.5)
			(connect_pads
				(clearance 0)
			)
			(min_thickness 0.25)
			(keepout
				(tracks not_allowed)
				(vias allowed)
				(pads allowed)
				(copperpour not_allowed)
				(footprints allowed)
			)
			(placement
				(enabled no)
				(sheetname "")
			)
			(fill
				(thermal_gap 0.5)
				(thermal_bridge_width 0.5)
				(island_removal_mode 0)
			)
			(polygon
				(pts
					(xy 428.0535 -20.574) (xy 428.0535 -20.066) (xy 427.6725 -20.066) (xy 427.6725 -20.574)
				)
			)
		)
	)
	(footprint ""
		(layer "B.Cu")
		(at 422.47312 -73.962514)
		(property "Reference" "C1R27"
			(at 0 0 0)
			(layer "B.SilkS")
			(hide yes)
			(effects
				(font
					(size 1.27 1.27)
				)
				(justify mirror)
			)
		)
		(property "Value" ""
			(at 0 0 0)
			(layer "B.Fab")
			(effects
				(font
					(size 1.27 1.27)
				)
				(justify mirror)
			)
		)
		(duplicate_pad_numbers_are_jumpers no)
		(fp_poly
			(pts
				(xy -0.3048 -0.1016) (xy -0.3048 0.9906) (xy 0.3048 0.9906) (xy 0.3048 -0.1016)
			)
			(stroke
				(width 0)
				(type default)
			)
			(fill no)
			(layer "B.CrtYd")
		)
		(fp_line
			(start -0.3048 -0.1016)
			(end 0.3048 -0.1016)
			(stroke
				(width 0.1)
				(type default)
			)
			(layer "B.Fab")
		)
		(fp_line
			(start -0.3048 0.9906)
			(end -0.3048 -0.1016)
			(stroke
				(width 0.1)
				(type default)
			)
			(layer "B.Fab")
		)
		(fp_line
			(start 0.3048 -0.1016)
			(end 0.3048 0.9906)
			(stroke
				(width 0.1)
				(type default)
			)
			(layer "B.Fab")
		)
		(fp_line
			(start 0.3048 0.9906)
			(end -0.3048 0.9906)
			(stroke
				(width 0.1)
				(type default)
			)
			(layer "B.Fab")
		)
		(pad "1" smd rect
			(at 0 0 180)
			(size 0.508 0.508)
			(layers "B.Cu" "B.Mask" "B.Paste")
			(net "P3V3_STBY")
		)
		(pad "2" smd rect
			(at 0 0.889 180)
			(size 0.508 0.508)
			(layers "B.Cu" "B.Mask" "B.Paste")
			(net "GND")
		)
		(zone
			(layer "B.Cu")
			(hatch none 0.5)
			(connect_pads
				(clearance 0)
			)
			(min_thickness 0.25)
			(keepout
				(tracks allowed)
				(vias not_allowed)
				(pads allowed)
				(copperpour not_allowed)
				(footprints allowed)
			)
			(placement
				(enabled no)
				(sheetname "")
			)
			(fill
				(thermal_gap 0.5)
				(thermal_bridge_width 0.5)
				(island_removal_mode 0)
			)
			(polygon
				(pts
					(xy 422.72712 -73.708514) (xy 422.21912 -73.708514) (xy 422.21912 -73.327514) (xy 422.72712 -73.327514)
				)
			)
		)
		(zone
			(layer "B.Cu")
			(hatch none 0.5)
			(connect_pads
				(clearance 0)
			)
			(min_thickness 0.25)
			(keepout
				(tracks not_allowed)
				(vias allowed)
				(pads allowed)
				(copperpour not_allowed)
				(footprints allowed)
			)
			(placement
				(enabled no)
				(sheetname "")
			)
			(fill
				(thermal_gap 0.5)
				(thermal_bridge_width 0.5)
				(island_removal_mode 0)
			)
			(polygon
				(pts
					(xy 422.72712 -73.327514) (xy 422.21912 -73.327514) (xy 422.21912 -73.708514) (xy 422.72712 -73.708514)
				)
			)
		)
	)
	(footprint ""
		(layer "B.Cu")
		(at 83.856068 -135.4074 -90)
		(property "Reference" "C8M5"
			(at -1.848866 0.752348 270)
			(unlocked yes)
			(layer "B.SilkS")
			(effects
				(font
					(size 1.27 0.9652)
					(thickness 0.1524)
				)
				(justify mirror)
			)
		)
		(property "Value" ""
			(at 0 0 90)
			(layer "B.Fab")
			(effects
				(font
					(size 1.27 1.27)
				)
				(justify mirror)
			)
		)
		(duplicate_pad_numbers_are_jumpers no)
		(fp_rect
			(start 0.500126 1.598422)
			(end -0.500126 -0.201422)
			(stroke
				(width 0)
				(type default)
			)
			(fill no)
			(layer "B.CrtYd")
		)
		(fp_line
			(start -0.500126 1.598422)
			(end 0.500126 1.598422)
			(stroke
				(width 0.1)
				(type default)
			)
			(layer "B.Fab")
		)
		(fp_line
			(start 0.500126 1.598422)
			(end 0.500126 -0.201422)
			(stroke
				(width 0.1)
				(type default)
			)
			(layer "B.Fab")
		)
		(fp_line
			(start -0.500126 -0.201422)
			(end -0.500126 1.598422)
			(stroke
				(width 0.1)
				(type default)
			)
			(layer "B.Fab")
		)
		(fp_line
			(start 0.500126 -0.201422)
			(end -0.500126 -0.201422)
			(stroke
				(width 0.1)
				(type default)
			)
			(layer "B.Fab")
		)
		(pad "1" smd rect
			(at 0 0 180)
			(size 0.889 0.9906)
			(layers "B.Cu" "B.Mask" "B.Paste")
			(net "PVDDQ_KLM")
		)
		(pad "2" smd rect
			(at 0 1.397 180)
			(size 0.889 0.9906)
			(layers "B.Cu" "B.Mask" "B.Paste")
			(net "GND")
		)
		(zone
			(layer "B.Cu")
			(hatch none 0.5)
			(connect_pads
				(clearance 0)
			)
			(min_thickness 0.25)
			(keepout
				(tracks not_allowed)
				(vias allowed)
				(pads allowed)
				(copperpour not_allowed)
				(footprints allowed)
			)
			(placement
				(enabled no)
				(sheetname "")
			)
			(fill
				(thermal_gap 0.5)
				(thermal_bridge_width 0.5)
				(island_removal_mode 0)
			)
			(polygon
				(pts
					(xy 82.903568 -134.9121) (xy 83.411568 -134.9121) (xy 83.411568 -135.9027) (xy 82.903568 -135.9027)
				)
			)
		)
		(zone
			(layer "B.Cu")
			(hatch none 0.5)
			(connect_pads
				(clearance 0)
			)
			(min_thickness 0.25)
			(keepout
				(tracks allowed)
				(vias not_allowed)
				(pads allowed)
				(copperpour not_allowed)
				(footprints allowed)
			)
			(placement
				(enabled no)
				(sheetname "")
			)
			(fill
				(thermal_gap 0.5)
				(thermal_bridge_width 0.5)
				(island_removal_mode 0)
			)
			(polygon
				(pts
					(xy 82.903568 -134.9121) (xy 83.411568 -134.9121) (xy 83.411568 -135.9027) (xy 82.903568 -135.9027)
				)
			)
		)
	)
)
